(kicad_pcb
	(version 20241229)
	(generator "pcbnew")
	(generator_version "9.0")
	(general
		(thickness 1.61)
		(legacy_teardrops no)
	)
	(paper "A3")
	(title_block
		(title "RDIMM DDR5 Tester")
		(date "2026-05-21")
		(rev "2.2.0")
		(company "Antmicro")
		(comment 9 "footprints 318-318 of 796")
	)
	(layers
		(0 "F.Cu" signal)
		(4 "In1.Cu" power)
		(6 "In2.Cu" mixed)
		(8 "In3.Cu" power)
		(10 "In4.Cu" mixed)
		(12 "In5.Cu" power)
		(14 "In6.Cu" mixed)
		(16 "In7.Cu" power)
		(18 "In8.Cu" power)
		(20 "In9.Cu" mixed)
		(22 "In10.Cu" power)
		(2 "B.Cu" signal)
		(9 "F.Adhes" user "F.Adhesive")
		(11 "B.Adhes" user "B.Adhesive")
		(13 "F.Paste" user)
		(15 "B.Paste" user)
		(5 "F.SilkS" user "F.Silkscreen")
		(7 "B.SilkS" user "B.Silkscreen")
		(1 "F.Mask" user)
		(3 "B.Mask" user)
		(17 "Dwgs.User" user "User.Drawings")
		(19 "Cmts.User" user "User.Comments")
		(21 "Eco1.User" user "User.Eco1")
		(23 "Eco2.User" user "User.Eco2")
		(25 "Edge.Cuts" user)
		(27 "Margin" user)
		(31 "F.CrtYd" user "F.Courtyard")
		(29 "B.CrtYd" user "B.Courtyard")
		(35 "F.Fab" user)
		(33 "B.Fab" user)
	)
	(footprint "antmicro-footprints:SW_DIP_SPSTx08_Slide_Copal_CVS-08xB_W5.9mm_P1mm"
		(layer "F.Cu")
		(at 243.953 141.601)
		(descr "SMD 8x-dip-switch SPST Copal_CVS-08xB, Slide, row spacing 5.9 mm (232 mils), body size  (see http://www.nidec-copal-electronics.com/e/catalog/switch/cvs.pdf)")
		(tags "SMD DIP Switch SPST Slide 5.9mm 232mil")
		(property "Reference" "SW4"
			(at -3.853 5.999 0)
			(layer "F.SilkS")
			(effects
				(font
					(size 0.7 0.7)
					(thickness 0.15)
				)
				(justify left bottom)
			)
		)
		(property "Value" "SW_CVS-08TB"
			(at -14.59 6.29 0)
			(layer "F.Fab")
			(effects
				(font
					(size 0.7 0.7)
					(thickness 0.15)
				)
				(justify left bottom)
			)
		)
		(property "Datasheet" "https://www.mouser.com/datasheet/2/972/cvs-1827291.pdf"
			(at 0 0 0)
			(layer "F.Fab")
			(hide yes)
			(effects
				(font
					(size 1.27 1.27)
					(thickness 0.15)
				)
			)
		)
		(property "MPN" "CVS-08TB"
			(at 0 0 0)
			(unlocked yes)
			(layer "F.Fab")
			(hide yes)
			(effects
				(font
					(size 1 1)
					(thickness 0.15)
				)
			)
		)
		(property "Manufacturer" "Nidec Components"
			(at 0 0 0)
			(unlocked yes)
			(layer "F.Fab")
			(hide yes)
			(effects
				(font
					(size 1 1)
					(thickness 0.15)
				)
			)
		)
		(property "Author" "Antmicro"
			(at 0 0 0)
			(unlocked yes)
			(layer "F.Fab")
			(hide yes)
			(effects
				(font
					(size 1 1)
					(thickness 0.15)
				)
			)
		)
		(property "License" "Apache-2.0"
			(at 0 0 0)
			(unlocked yes)
			(layer "F.Fab")
			(hide yes)
			(effects
				(font
					(size 1 1)
					(thickness 0.15)
				)
			)
		)
		(property ki_fp_filters "SW?DIP?x2*")
		(sheetname "/Supply/")
		(sheetfile "supply.kicad_sch")
		(attr smd)
		(fp_line
			(start -1.561 -4.912)
			(end 1.56 -4.912)
			(stroke
				(width 0.15)
				(type solid)
			)
			(layer "F.SilkS")
		)
		(fp_line
			(start -1.561 4.91)
			(end 1.56 4.91)
			(stroke
				(width 0.15)
				(type solid)
			)
			(layer "F.SilkS")
		)
		(fp_circle
			(center -3.31 -4.2)
			(end -3.261 -4.2)
			(stroke
				(width 0.15)
				(type solid)
			)
			(fill yes)
			(layer "F.SilkS")
		)
		(fp_rect
			(start -3.601 -5)
			(end 3.598 4.998)
			(stroke
				(width 0.05)
				(type solid)
			)
			(fill no)
			(layer "F.CrtYd")
		)
		(fp_line
			(start -2.351 -3.5)
			(end -1.351 -4.5)
			(stroke
				(width 0.15)
				(type solid)
			)
			(layer "F.Fab")
		)
		(fp_line
			(start -2.351 4.498)
			(end -2.351 -3.5)
			(stroke
				(width 0.15)
				(type solid)
			)
			(layer "F.Fab")
		)
		(fp_line
			(start -1.351 -4.5)
			(end 2.35 -4.5)
			(stroke
				(width 0.15)
				(type solid)
			)
			(layer "F.Fab")
		)
		(fp_line
			(start -1 -3.75)
			(end -1 -3.25)
			(stroke
				(width 0.15)
				(type solid)
			)
			(layer "F.Fab")
		)
		(fp_line
			(start -1 -3.65)
			(end -0.335 -3.65)
			(stroke
				(width 0.15)
				(type solid)
			)
			(layer "F.Fab")
		)
		(fp_line
			(start -1 -3.551)
			(end -0.335 -3.551)
			(stroke
				(width 0.15)
				(type solid)
			)
			(layer "F.Fab")
		)
		(fp_line
			(start -1 -3.451)
			(end -0.335 -3.451)
			(stroke
				(width 0.15)
				(type solid)
			)
			(layer "F.Fab")
		)
		(fp_line
			(start -1 -3.351)
			(end -0.335 -3.351)
			(stroke
				(width 0.15)
				(type solid)
			)
			(layer "F.Fab")
		)
		(fp_line
			(start -1 -3.25)
			(end 0.998 -3.25)
			(stroke
				(width 0.15)
				(type solid)
			)
			(layer "F.Fab")
		)
		(fp_line
			(start -1 -2.75)
			(end -1 -2.25)
			(stroke
				(width 0.15)
				(type solid)
			)
			(layer "F.Fab")
		)
		(fp_line
			(start -1 -2.65)
			(end -0.335 -2.65)
			(stroke
				(width 0.15)
				(type solid)
			)
			(layer "F.Fab")
		)
		(fp_line
			(start -1 -2.551)
			(end -0.335 -2.551)
			(stroke
				(width 0.15)
				(type solid)
			)
			(layer "F.Fab")
		)
		(fp_line
			(start -1 -2.452)
			(end -0.335 -2.452)
			(stroke
				(width 0.15)
				(type solid)
			)
			(layer "F.Fab")
		)
		(fp_line
			(start -1 -2.351)
			(end -0.335 -2.351)
			(stroke
				(width 0.15)
				(type solid)
			)
			(layer "F.Fab")
		)
		(fp_line
			(start -1 -2.25)
			(end 0.998 -2.25)
			(stroke
				(width 0.15)
				(type solid)
			)
			(layer "F.Fab")
		)
		(fp_line
			(start -1 -1.75)
			(end -1 -1.25)
			(stroke
				(width 0.15)
				(type solid)
			)
			(layer "F.Fab")
		)
		(fp_line
			(start -1 -1.651)
			(end -0.335 -1.651)
			(stroke
				(width 0.15)
				(type solid)
			)
			(layer "F.Fab")
		)
		(fp_line
			(start -1 -1.551)
			(end -0.335 -1.551)
			(stroke
				(width 0.15)
				(type solid)
			)
			(layer "F.Fab")
		)
		(fp_line
			(start -1 -1.45)
			(end -0.335 -1.45)
			(stroke
				(width 0.15)
				(type solid)
			)
			(layer "F.Fab")
		)
		(fp_line
			(start -1 -1.351)
			(end -0.335 -1.351)
			(stroke
				(width 0.15)
				(type solid)
			)
			(layer "F.Fab")
		)
		(fp_line
			(start -1 -1.25)
			(end 0.998 -1.25)
			(stroke
				(width 0.15)
				(type solid)
			)
			(layer "F.Fab")
		)
		(fp_line
			(start -1 -0.75)
			(end -1 -0.25)
			(stroke
				(width 0.15)
				(type solid)
			)
			(layer "F.Fab")
		)
		(fp_line
			(start -1 -0.652)
			(end -0.335 -0.652)
			(stroke
				(width 0.15)
				(type solid)
			)
			(layer "F.Fab")
		)
		(fp_line
			(start -1 -0.552)
			(end -0.335 -0.552)
			(stroke
				(width 0.15)
				(type solid)
			)
			(layer "F.Fab")
		)
		(fp_line
			(start -1 -0.452)
			(end -0.335 -0.452)
			(stroke
				(width 0.15)
				(type solid)
			)
			(layer "F.Fab")
		)
		(fp_line
			(start -1 -0.351)
			(end -0.335 -0.351)
			(stroke
				(width 0.15)
				(type solid)
			)
			(layer "F.Fab")
		)
		(fp_line
			(start -1 -0.25)
			(end 0.998 -0.25)
			(stroke
				(width 0.15)
				(type solid)
			)
			(layer "F.Fab")
		)
		(fp_line
			(start -1 0.248)
			(end -1 0.748)
			(stroke
				(width 0.15)
				(type solid)
			)
			(layer "F.Fab")
		)
		(fp_line
			(start -1 0.349)
			(end -0.335 0.349)
			(stroke
				(width 0.15)
				(type solid)
			)
			(layer "F.Fab")
		)
		(fp_line
			(start -1 0.45)
			(end -0.335 0.45)
			(stroke
				(width 0.15)
				(type solid)
			)
			(layer "F.Fab")
		)
		(fp_line
			(start -1 0.55)
			(end -0.335 0.55)
			(stroke
				(width 0.15)
				(type solid)
			)
			(layer "F.Fab")
		)
		(fp_line
			(start -1 0.65)
			(end -0.335 0.65)
			(stroke
				(width 0.15)
				(type solid)
			)
			(layer "F.Fab")
		)
		(fp_line
			(start -1 0.748)
			(end -0.335 0.748)
			(stroke
				(width 0.15)
				(type solid)
			)
			(layer "F.Fab")
		)
		(fp_line
			(start -1 0.748)
			(end 0.998 0.748)
			(stroke
				(width 0.15)
				(type solid)
			)
			(layer "F.Fab")
		)
		(fp_line
			(start -1 1.249)
			(end -1 1.749)
			(stroke
				(width 0.15)
				(type solid)
			)
			(layer "F.Fab")
		)
		(fp_line
			(start -1 1.35)
			(end -0.335 1.35)
			(stroke
				(width 0.15)
				(type solid)
			)
			(layer "F.Fab")
		)
		(fp_line
			(start -1 1.449)
			(end -0.335 1.449)
			(stroke
				(width 0.15)
				(type solid)
			)
			(layer "F.Fab")
		)
		(fp_line
			(start -1 1.55)
			(end -0.335 1.55)
			(stroke
				(width 0.15)
				(type solid)
			)
			(layer "F.Fab")
		)
		(fp_line
			(start -1 1.648)
			(end -0.335 1.648)
			(stroke
				(width 0.15)
				(type solid)
			)
			(layer "F.Fab")
		)
		(fp_line
			(start -1 1.749)
			(end -0.335 1.749)
			(stroke
				(width 0.15)
				(type solid)
			)
			(layer "F.Fab")
		)
		(fp_line
			(start -1 1.749)
			(end 0.998 1.749)
			(stroke
				(width 0.15)
				(type solid)
			)
			(layer "F.Fab")
		)
		(fp_line
			(start -1 2.249)
			(end -1 2.749)
			(stroke
				(width 0.15)
				(type solid)
			)
			(layer "F.Fab")
		)
		(fp_line
			(start -1 2.35)
			(end -0.335 2.35)
			(stroke
				(width 0.15)
				(type solid)
			)
			(layer "F.Fab")
		)
		(fp_line
			(start -1 2.45)
			(end -0.335 2.45)
			(stroke
				(width 0.15)
				(type solid)
			)
			(layer "F.Fab")
		)
		(fp_line
			(start -1 2.548)
			(end -0.335 2.548)
			(stroke
				(width 0.15)
				(type solid)
			)
			(layer "F.Fab")
		)
		(fp_line
			(start -1 2.648)
			(end -0.335 2.648)
			(stroke
				(width 0.15)
				(type solid)
			)
			(layer "F.Fab")
		)
		(fp_line
			(start -1 2.749)
			(end -0.335 2.749)
			(stroke
				(width 0.15)
				(type solid)
			)
			(layer "F.Fab")
		)
		(fp_line
			(start -1 2.749)
			(end 0.998 2.749)
			(stroke
				(width 0.15)
				(type solid)
			)
			(layer "F.Fab")
		)
		(fp_line
			(start -1 3.249)
			(end -1 3.749)
			(stroke
				(width 0.15)
				(type solid)
			)
			(layer "F.Fab")
		)
		(fp_line
			(start -1 3.35)
			(end -0.335 3.35)
			(stroke
				(width 0.15)
				(type solid)
			)
			(layer "F.Fab")
		)
		(fp_line
			(start -1 3.45)
			(end -0.335 3.45)
			(stroke
				(width 0.15)
				(type solid)
			)
			(layer "F.Fab")
		)
		(fp_line
			(start -1 3.548)
			(end -0.335 3.548)
			(stroke
				(width 0.15)
				(type solid)
			)
			(layer "F.Fab")
		)
		(fp_line
			(start -1 3.648)
			(end -0.335 3.648)
			(stroke
				(width 0.15)
				(type solid)
			)
			(layer "F.Fab")
		)
		(fp_line
			(start -1 3.749)
			(end -0.335 3.749)
			(stroke
				(width 0.15)
				(type solid)
			)
			(layer "F.Fab")
		)
		(fp_line
			(start -1 3.749)
			(end 0.998 3.749)
			(stroke
				(width 0.15)
				(type solid)
			)
			(layer "F.Fab")
		)
		(fp_line
			(start -0.335 -3.75)
			(end -0.335 -3.25)
			(stroke
				(width 0.15)
				(type solid)
			)
			(layer "F.Fab")
		)
		(fp_line
			(start -0.335 -2.75)
			(end -0.335 -2.25)
			(stroke
				(width 0.15)
				(type solid)
			)
			(layer "F.Fab")
		)
		(fp_line
			(start -0.335 -1.75)
			(end -0.335 -1.25)
			(stroke
				(width 0.15)
				(type solid)
			)
			(layer "F.Fab")
		)
		(fp_line
			(start -0.335 -0.75)
			(end -0.335 -0.25)
			(stroke
				(width 0.15)
				(type solid)
			)
			(layer "F.Fab")
		)
		(fp_line
			(start -0.335 0.248)
			(end -0.335 0.748)
			(stroke
				(width 0.15)
				(type solid)
			)
			(layer "F.Fab")
		)
		(fp_line
			(start -0.335 1.249)
			(end -0.335 1.749)
			(stroke
				(width 0.15)
				(type solid)
			)
			(layer "F.Fab")
		)
		(fp_line
			(start -0.335 2.249)
			(end -0.335 2.749)
			(stroke
				(width 0.15)
				(type solid)
			)
			(layer "F.Fab")
		)
		(fp_line
			(start -0.335 3.249)
			(end -0.335 3.749)
			(stroke
				(width 0.15)
				(type solid)
			)
			(layer "F.Fab")
		)
		(fp_line
			(start 0.998 -3.75)
			(end -1 -3.75)
			(stroke
				(width 0.15)
				(type solid)
			)
			(layer "F.Fab")
		)
		(fp_line
			(start 0.998 -3.25)
			(end 0.998 -3.75)
			(stroke
				(width 0.15)
				(type solid)
			)
			(layer "F.Fab")
		)
		(fp_line
			(start 0.998 -2.75)
			(end -1 -2.75)
			(stroke
				(width 0.15)
				(type solid)
			)
			(layer "F.Fab")
		)
		(fp_line
			(start 0.998 -2.25)
			(end 0.998 -2.75)
			(stroke
				(width 0.15)
				(type solid)
			)
			(layer "F.Fab")
		)
		(fp_line
			(start 0.998 -1.75)
			(end -1 -1.75)
			(stroke
				(width 0.15)
				(type solid)
			)
			(layer "F.Fab")
		)
		(fp_line
			(start 0.998 -1.25)
			(end 0.998 -1.75)
			(stroke
				(width 0.15)
				(type solid)
			)
			(layer "F.Fab")
		)
		(fp_line
			(start 0.998 -0.75)
			(end -1 -0.75)
			(stroke
				(width 0.15)
				(type solid)
			)
			(layer "F.Fab")
		)
		(fp_line
			(start 0.998 -0.25)
			(end 0.998 -0.75)
			(stroke
				(width 0.15)
				(type solid)
			)
			(layer "F.Fab")
		)
		(fp_line
			(start 0.998 0.248)
			(end -1 0.248)
			(stroke
				(width 0.15)
				(type solid)
			)
			(layer "F.Fab")
		)
		(fp_line
			(start 0.998 0.748)
			(end 0.998 0.248)
			(stroke
				(width 0.15)
				(type solid)
			)
			(layer "F.Fab")
		)
		(fp_line
			(start 0.998 1.249)
			(end -1 1.249)
			(stroke
				(width 0.15)
				(type solid)
			)
			(layer "F.Fab")
		)
		(fp_line
			(start 0.998 1.749)
			(end 0.998 1.249)
			(stroke
				(width 0.15)
				(type solid)
			)
			(layer "F.Fab")
		)
		(fp_line
			(start 0.998 2.249)
			(end -1 2.249)
			(stroke
				(width 0.15)
				(type solid)
			)
			(layer "F.Fab")
		)
		(fp_line
			(start 0.998 2.749)
			(end 0.998 2.249)
			(stroke
				(width 0.15)
				(type solid)
			)
			(layer "F.Fab")
		)
		(fp_line
			(start 0.998 3.249)
			(end -1 3.249)
			(stroke
				(width 0.15)
				(type solid)
			)
			(layer "F.Fab")
		)
		(fp_line
			(start 0.998 3.749)
			(end 0.998 3.249)
			(stroke
				(width 0.15)
				(type solid)
			)
			(layer "F.Fab")
		)
		(fp_line
			(start 2.35 -4.5)
			(end 2.35 4.498)
			(stroke
				(width 0.15)
				(type solid)
			)
			(layer "F.Fab")
		)
		(fp_line
			(start 2.35 4.498)
			(end -2.351 4.498)
			(stroke
				(width 0.15)
				(type solid)
			)
			(layer "F.Fab")
		)
		(fp_text user "Author: Antmicro"
			(at -14.59 8.29 0)
			(layer "F.Fab")
			(effects
				(font
					(size 0.7 0.7)
					(thickness 0.15)
				)
				(justify left bottom)
			)
		)
		(fp_text user "License: Apache-2.0"
			(at -14.59 10.69 0)
			(layer "F.Fab")
			(effects
				(font
					(size 0.7 0.7)
					(thickness 0.15)
				)
				(justify left bottom)
			)
		)
		(fp_text user "${REFERENCE}"
			(at -14.59 11.89 0)
			(layer "F.Fab")
			(effects
				(font
					(size 0.7 0.7)
					(thickness 0.15)
				)
				(justify left bottom)
			)
		)
		(fp_text user "on"
			(at -1.56 0.69 90)
			(layer "F.Fab")
			(effects
				(font
					(size 0.7 0.7)
					(thickness 0.15)
				)
				(justify left bottom)
			)
		)
		(pad "1" smd rect
			(at -2.952 -3.5)
			(size 1.2 0.5)
			(layers "F.Cu" "F.Mask" "F.Paste")
			(net 138 "/Supply/PB_CTRL_OUT")
			(pinfunction "1")
			(pintype "passive")
		)
		(pad "2" smd rect
			(at -2.952 -2.5)
			(size 1.2 0.5)
			(layers "F.Cu" "F.Mask" "F.Paste")
			(net 157 "/Supply/~{PB_CTRL_INT}")
			(pinfunction "2")
			(pintype "passive")
		)
		(pad "3" smd rect
			(at -2.952 -1.5)
			(size 1.2 0.5)
			(layers "F.Cu" "F.Mask" "F.Paste")
			(net 404 "IN1")
			(pinfunction "3")
			(pintype "passive")
		)
		(pad "4" smd rect
			(at -2.952 -0.5)
			(size 1.2 0.5)
			(layers "F.Cu" "F.Mask" "F.Paste")
			(net 405 "IN2")
			(pinfunction "4")
			(pintype "passive")
		)
		(pad "5" smd rect
			(at -2.952 0.498)
			(size 1.2 0.5)
			(layers "F.Cu" "F.Mask" "F.Paste")
			(net 773 "MODE2")
			(pinfunction "5")
			(pintype "passive")
		)
		(pad "6" smd rect
			(at -2.952 1.499)
			(size 1.2 0.5)
			(layers "F.Cu" "F.Mask" "F.Paste")
			(net 626 "USER_IN")
			(pinfunction "6")
			(pintype "passive")
		)
		(pad "7" smd rect
			(at -2.952 2.499)
			(size 1.2 0.5)
			(layers "F.Cu" "F.Mask" "F.Paste")
			(net 749 "/I^{2}C + I3C/PWR.SCL")
			(pinfunction "7")
			(pintype "passive")
		)
		(pad "8" smd rect
			(at -2.952 3.499)
			(size 1.2 0.5)
			(layers "F.Cu" "F.Mask" "F.Paste")
			(net 197 "FTDI_DIS")
			(pinfunction "8")
			(pintype "passive")
		)
		(pad "9" smd rect
			(at 2.95 3.499)
			(size 1.2 0.5)
			(layers "F.Cu" "F.Mask" "F.Paste")
			(net 1 "GND")
			(pinfunction "9")
			(pintype "passive")
		)
		(pad "10" smd rect
			(at 2.95 2.499)
			(size 1.2 0.5)
			(layers "F.Cu" "F.Mask" "F.Paste")
			(net 215 "/Supply/QDCDC2_SCL")
			(pinfunction "10")
			(pintype "passive")
		)
		(pad "11" smd rect
			(at 2.95 1.499)
			(size 1.2 0.5)
			(layers "F.Cu" "F.Mask" "F.Paste")
			(net 486 "Net-(R87-Pad1)")
			(pinfunction "11")
			(pintype "passive")
		)
		(pad "12" smd rect
			(at 2.95 0.498)
			(size 1.2 0.5)
			(layers "F.Cu" "F.Mask" "F.Paste")
			(net 1 "GND")
			(pinfunction "12")
			(pintype "passive")
		)
		(pad "13" smd rect
			(at 2.95 -0.5)
			(size 1.2 0.5)
			(layers "F.Cu" "F.Mask" "F.Paste")
			(net 1 "GND")
			(pinfunction "13")
			(pintype "passive")
		)
		(pad "14" smd rect
			(at 2.95 -1.5)
			(size 1.2 0.5)
			(layers "F.Cu" "F.Mask" "F.Paste")
			(net 1 "GND")
			(pinfunction "14")
			(pintype "passive")
		)
		(pad "15" smd rect
			(at 2.95 -2.5)
			(size 1.2 0.5)
			(layers "F.Cu" "F.Mask" "F.Paste")
			(net 137 "/Supply/~{PB_CTRL_CLR}")
			(pinfunction "15")
			(pintype "passive")
		)
		(pad "16" smd rect
			(at 2.95 -3.5)
			(size 1.2 0.5)
			(layers "F.Cu" "F.Mask" "F.Paste")
			(net 50 "/Supply/SEQ_EN")
			(pinfunction "16")
			(pintype "passive")
		)
		(pad "17" smd rect
			(at -2.15 -4.5)
			(size 0.7 0.7)
			(layers "F.Cu" "F.Mask" "F.Paste")
			(net 1 "GND")
			(pinfunction "17")
			(pintype "power_in")
		)
		(pad "17" smd rect
			(at -2.15 4.498)
			(size 0.7 0.7)
			(layers "F.Cu" "F.Mask" "F.Paste")
			(net 1 "GND")
			(pinfunction "17")
			(pintype "power_in")
		)
		(pad "17" smd rect
			(at 2.148 -4.5)
			(size 0.7 0.7)
			(layers "F.Cu" "F.Mask" "F.Paste")
			(net 1 "GND")
			(pinfunction "17")
			(pintype "power_in")
		)
		(pad "17" smd rect
			(at 2.148 4.498)
			(size 0.7 0.7)
			(layers "F.Cu" "F.Mask" "F.Paste")
			(net 1 "GND")
			(pinfunction "17")
			(pintype "power_in")
		)
	)
)
